# T6G (Grand Teton) — schematic netlist excerpt (pin names and nets, part order shuffled) for the footprints in the layout excerpt that follows; sources: Cadence DE-HDL packaged netlist, KiCad conversion of 04192023_DAF0TMB3IC0_F0TG_MB_C_brd_V02_OCP.brd

R1573  Q_RES  49.9 1% CHIP  pkg 0402LF  page 91 : A = I3C_SPD_DDRAF_CPU0_SCL ; B = I3C_SPD_DDRF_CPU0_SCL
R309  Q_RES  33 5% CHIP  pkg 0402LF  page 151 : A = SMB_VR_3V3AUX_SDA ; B = SMB_VR_3V3STBY_SDA
C990  Q_CAP  100UF 4V 20% X6S  pkg C0805  page 312 : A = P1V8_CPU0_RT_1D ; B = GND

(kicad_pcb
	(version 20260206)
	(generator "pcbnew")
	(generator_version "10.0")
	(general
		(thickness 1.6)
		(legacy_teardrops no)
	)
	(paper "A4")
	(title_block
		(title "04192023_DAF0TMB3IC0_F0TG_MB_C_brd_V02_OCP.brd")
		(comment 1 "Grand Teton / footprints 5161-5163 of 8354")
	)
	(layers
		(0 "F.Cu" signal "TOP")
		(4 "In1.Cu" signal "GND")
		(6 "In2.Cu" signal "IN1")
		(8 "In3.Cu" signal "GND1")
		(10 "In4.Cu" signal "IN2")
		(12 "In5.Cu" signal "GND2")
		(14 "In6.Cu" signal "IN3")
		(16 "In7.Cu" signal "GND3")
		(18 "In8.Cu" signal "VCC")
		(20 "In9.Cu" signal "VCC1")
		(22 "In10.Cu" signal "GND4")
		(24 "In11.Cu" signal "IN4")
		(26 "In12.Cu" signal "GND5")
		(28 "In13.Cu" signal "IN5")
		(30 "In14.Cu" signal "GND6")
		(32 "In15.Cu" signal "IN6")
		(34 "In16.Cu" signal "GND7")
		(2 "B.Cu" signal "BOTTOM")
		(9 "F.Adhes" user "F.Adhesive")
		(11 "B.Adhes" user "B.Adhesive")
		(13 "F.Paste" user "Package Geometry/Pastemask Top")
		(15 "B.Paste" user "Package Geometry/Pastemask Bottom")
		(5 "F.SilkS" user "Ref Des/Silkscreen Top")
		(7 "B.SilkS" user "Ref Des/Silkscreen Bottom")
		(1 "F.Mask" user "Board Geometry/Soldermask Top")
		(3 "B.Mask" user "Board Geometry/Soldermask Bottom")
		(17 "Dwgs.User" user "User.Drawings")
		(19 "Cmts.User" user "User.Comments")
		(21 "Eco1.User" user "User.Eco1")
		(23 "Eco2.User" user "User.Eco2")
		(25 "Edge.Cuts" user "Board Geometry/Outline")
		(27 "Margin" user)
		(31 "F.CrtYd" user "Package Geometry/Place Bound Top")
		(29 "B.CrtYd" user "Package Geometry/Place Bound Bottom")
		(35 "F.Fab" user "Ref Des/Assembly Top")
		(33 "B.Fab" user "Ref Des/Assembly Bottom")
	)
	(footprint ""
		(layer "B.Cu")
		(at 268.892528 -194.893946 180)
		(property "Reference" "R1573"
			(at 0 0 0)
			(layer "B.SilkS")
			(hide yes)
			(effects
				(font
					(size 1.27 1.27)
				)
				(justify mirror)
			)
		)
		(property "Value" ""
			(at 0 0 0)
			(layer "B.Fab")
			(effects
				(font
					(size 1.27 1.27)
				)
				(justify mirror)
			)
		)
		(duplicate_pad_numbers_are_jumpers no)
		(fp_line
			(start 0.7874 0.4064)
			(end 0.7874 -0.4064)
			(stroke
				(width 0.1524)
				(type default)
			)
			(layer "B.SilkS")
		)
		(fp_line
			(start 0.7874 -0.4064)
			(end -0.7874 -0.4064)
			(stroke
				(width 0.1524)
				(type default)
			)
			(layer "B.SilkS")
		)
		(fp_line
			(start -0.7874 0.4064)
			(end 0.7874 0.4064)
			(stroke
				(width 0.1524)
				(type default)
			)
			(layer "B.SilkS")
		)
		(fp_line
			(start -0.7874 -0.4064)
			(end -0.7874 0.4064)
			(stroke
				(width 0.1524)
				(type default)
			)
			(layer "B.SilkS")
		)
		(fp_line
			(start 0.67945 0.3048)
			(end 0.67945 -0.305054)
			(stroke
				(width 0.1)
				(type default)
			)
			(layer "B.Fab")
		)
		(fp_line
			(start 0.67945 -0.305054)
			(end 0.12065 -0.305054)
			(stroke
				(width 0.1)
				(type default)
			)
			(layer "B.Fab")
		)
		(fp_line
			(start 0.12065 0.3048)
			(end 0.67945 0.3048)
			(stroke
				(width 0.1)
				(type default)
			)
			(layer "B.Fab")
		)
		(fp_line
			(start 0.12065 0.2794)
			(end 0.12065 0.3048)
			(stroke
				(width 0.1)
				(type default)
			)
			(layer "B.Fab")
		)
		(fp_line
			(start 0.12065 -0.2794)
			(end -0.12065 -0.2794)
			(stroke
				(width 0.1)
				(type default)
			)
			(layer "B.Fab")
		)
		(fp_line
			(start 0.12065 -0.305054)
			(end 0.12065 -0.2794)
			(stroke
				(width 0.1)
				(type default)
			)
			(layer "B.Fab")
		)
		(fp_line
			(start -0.120396 0.3048)
			(end -0.120396 0.2794)
			(stroke
				(width 0.1)
				(type default)
			)
			(layer "B.Fab")
		)
		(fp_line
			(start -0.120396 0.2794)
			(end 0.12065 0.2794)
			(stroke
				(width 0.1)
				(type default)
			)
			(layer "B.Fab")
		)
		(fp_line
			(start -0.12065 -0.2794)
			(end -0.12065 -0.3048)
			(stroke
				(width 0.1)
				(type default)
			)
			(layer "B.Fab")
		)
		(fp_line
			(start -0.12065 -0.3048)
			(end -0.67945 -0.3048)
			(stroke
				(width 0.1)
				(type default)
			)
			(layer "B.Fab")
		)
		(fp_line
			(start -0.67945 0.3048)
			(end -0.120396 0.3048)
			(stroke
				(width 0.1)
				(type default)
			)
			(layer "B.Fab")
		)
		(fp_line
			(start -0.67945 -0.3048)
			(end -0.67945 0.3048)
			(stroke
				(width 0.1)
				(type default)
			)
			(layer "B.Fab")
		)
		(pad "1" smd circle
			(at 0.40005 0)
			(size 0 0)
			(layers "B.Cu" "B.Mask" "B.Paste")
			(net "I3C_SPD_DDRAF_CPU0_SCL")
		)
		(pad "2" smd circle
			(at -0.40005 0)
			(size 0 0)
			(layers "B.Cu" "B.Mask" "B.Paste")
			(net "I3C_SPD_DDRF_CPU0_SCL")
		)
	)
	(footprint ""
		(layer "B.Cu")
		(at 393.745466 -395.466062 -90)
		(property "Reference" "C990"
			(at 0 0 90)
			(layer "B.SilkS")
			(hide yes)
			(effects
				(font
					(size 1.27 1.27)
				)
				(justify mirror)
			)
		)
		(property "Value" ""
			(at 0 0 90)
			(layer "B.Fab")
			(effects
				(font
					(size 1.27 1.27)
				)
				(justify mirror)
			)
		)
		(duplicate_pad_numbers_are_jumpers no)
		(fp_line
			(start -1.524 0.762)
			(end 1.524 0.762)
			(stroke
				(width 0.1524)
				(type default)
			)
			(layer "B.SilkS")
		)
		(fp_line
			(start 1.524 0.762)
			(end 1.524 -0.762)
			(stroke
				(width 0.1524)
				(type default)
			)
			(layer "B.SilkS")
		)
		(fp_line
			(start -1.524 -0.762)
			(end -1.524 0.762)
			(stroke
				(width 0.1524)
				(type default)
			)
			(layer "B.SilkS")
		)
		(fp_line
			(start 1.524 -0.762)
			(end -1.524 -0.762)
			(stroke
				(width 0.1524)
				(type default)
			)
			(layer "B.SilkS")
		)
		(fp_line
			(start -1.1049 0.724916)
			(end -1.1049 -0.724916)
			(stroke
				(width 0.1)
				(type default)
			)
			(layer "B.Fab")
		)
		(fp_line
			(start 1.1049 0.724916)
			(end -1.1049 0.724916)
			(stroke
				(width 0.1)
				(type default)
			)
			(layer "B.Fab")
		)
		(fp_line
			(start -1.1049 -0.724916)
			(end 1.1049 -0.724916)
			(stroke
				(width 0.1)
				(type default)
			)
			(layer "B.Fab")
		)
		(fp_line
			(start 1.1049 -0.724916)
			(end 1.1049 0.724916)
			(stroke
				(width 0.1)
				(type default)
			)
			(layer "B.Fab")
		)
		(pad "1" smd rect
			(at 0.889 0 270)
			(size 1.016 1.27)
			(layers "B.Cu" "B.Mask" "B.Paste")
			(net "P1V8_CPU0_RT_1D")
		)
		(pad "2" smd rect
			(at -0.889 0 270)
			(size 1.016 1.27)
			(layers "B.Cu" "B.Mask" "B.Paste")
			(net "GND")
		)
	)
	(footprint ""
		(layer "B.Cu")
		(at 93.4212 -139.192)
		(property "Reference" "R309"
			(at 0 0 0)
			(layer "B.SilkS")
			(hide yes)
			(effects
				(font
					(size 1.27 1.27)
				)
				(justify mirror)
			)
		)
		(property "Value" ""
			(at 0 0 0)
			(layer "B.Fab")
			(effects
				(font
					(size 1.27 1.27)
				)
				(justify mirror)
			)
		)
		(duplicate_pad_numbers_are_jumpers no)
		(fp_line
			(start -0.7874 -0.4064)
			(end -0.7874 0.4064)
			(stroke
				(width 0.1524)
				(type default)
			)
			(layer "B.SilkS")
		)
		(fp_line
			(start -0.7874 0.4064)
			(end 0.7874 0.4064)
			(stroke
				(width 0.1524)
				(type default)
			)
			(layer "B.SilkS")
		)
		(fp_line
			(start 0.7874 -0.4064)
			(end -0.7874 -0.4064)
			(stroke
				(width 0.1524)
				(type default)
			)
			(layer "B.SilkS")
		)
		(fp_line
			(start 0.7874 0.4064)
			(end 0.7874 -0.4064)
			(stroke
				(width 0.1524)
				(type default)
			)
			(layer "B.SilkS")
		)
		(fp_line
			(start -0.67945 -0.3048)
			(end -0.67945 0.3048)
			(stroke
				(width 0.1)
				(type default)
			)
			(layer "B.Fab")
		)
		(fp_line
			(start -0.67945 0.3048)
			(end -0.120396 0.3048)
			(stroke
				(width 0.1)
				(type default)
			)
			(layer "B.Fab")
		)
		(fp_line
			(start -0.12065 -0.3048)
			(end -0.67945 -0.3048)
			(stroke
				(width 0.1)
				(type default)
			)
			(layer "B.Fab")
		)
		(fp_line
			(start -0.12065 -0.2794)
			(end -0.12065 -0.3048)
			(stroke
				(width 0.1)
				(type default)
			)
			(layer "B.Fab")
		)
		(fp_line
			(start -0.120396 0.2794)
			(end 0.12065 0.2794)
			(stroke
				(width 0.1)
				(type default)
			)
			(layer "B.Fab")
		)
		(fp_line
			(start -0.120396 0.3048)
			(end -0.120396 0.2794)
			(stroke
				(width 0.1)
				(type default)
			)
			(layer "B.Fab")
		)
		(fp_line
			(start 0.12065 -0.305054)
			(end 0.12065 -0.2794)
			(stroke
				(width 0.1)
				(type default)
			)
			(layer "B.Fab")
		)
		(fp_line
			(start 0.12065 -0.2794)
			(end -0.12065 -0.2794)
			(stroke
				(width 0.1)
				(type default)
			)
			(layer "B.Fab")
		)
		(fp_line
			(start 0.12065 0.2794)
			(end 0.12065 0.3048)
			(stroke
				(width 0.1)
				(type default)
			)
			(layer "B.Fab")
		)
		(fp_line
			(start 0.12065 0.3048)
			(end 0.67945 0.3048)
			(stroke
				(width 0.1)
				(type default)
			)
			(layer "B.Fab")
		)
		(fp_line
			(start 0.67945 -0.305054)
			(end 0.12065 -0.305054)
			(stroke
				(width 0.1)
				(type default)
			)
			(layer "B.Fab")
		)
		(fp_line
			(start 0.67945 0.3048)
			(end 0.67945 -0.305054)
			(stroke
				(width 0.1)
				(type default)
			)
			(layer "B.Fab")
		)
		(pad "1" smd circle
			(at 0.40005 0 180)
			(size 0 0)
			(layers "B.Cu" "B.Mask" "B.Paste")
			(net "SMB_VR_3V3AUX_SDA")
		)
		(pad "2" smd circle
			(at -0.40005 0 180)
			(size 0 0)
			(layers "B.Cu" "B.Mask" "B.Paste")
			(net "SMB_VR_3V3STBY_SDA")
		)
	)
)
